# S9S_MB_2U (Grand Teton) — schematic netlist excerpt (pin names and nets, part order shuffled) for the footprints in the layout excerpt that follows; sources: Cadence DE-HDL packaged netlist, KiCad conversion of 03242023_DA0F0TMBIJ0_F0T_Motherboard_J_brd_V01_OCP.brd

ME15  ME_DUMMY_SYMBOL  PICKUP_SMDC20 EMPTY  pkg PICKUP_SMDC20  page 312
C1028  Q_CAP  22UF 4V 20% X6S  pkg C0402  page 74 : A = PVCCIN_CPU0 ; B = GND
R3082  Q_RES  130 1% CHIP  pkg 0402LF  page 256 : A = LED_RST_PLD_CPU1_DRAM_AB_N ; B = P3V3_AUX

(kicad_pcb
	(version 20260206)
	(generator "pcbnew")
	(generator_version "10.0")
	(general
		(thickness 1.6)
		(legacy_teardrops no)
	)
	(paper "A4")
	(title_block
		(title "03242023_DA0F0TMBIJ0_F0T_Motherboard_J_brd_V01_OCP.brd")
		(comment 1 "Grand Teton / footprints 1983-1985 of 6105")
	)
	(layers
		(0 "F.Cu" signal "TOP")
		(4 "In1.Cu" signal "GND")
		(6 "In2.Cu" signal "IN1")
		(8 "In3.Cu" signal "GND1")
		(10 "In4.Cu" signal "IN2")
		(12 "In5.Cu" signal "GND2")
		(14 "In6.Cu" signal "IN3")
		(16 "In7.Cu" signal "GND3")
		(18 "In8.Cu" signal "VCC")
		(20 "In9.Cu" signal "VCC1")
		(22 "In10.Cu" signal "GND4")
		(24 "In11.Cu" signal "IN4")
		(26 "In12.Cu" signal "GND5")
		(28 "In13.Cu" signal "IN5")
		(30 "In14.Cu" signal "GND6")
		(32 "In15.Cu" signal "IN6")
		(34 "In16.Cu" signal "GND7")
		(2 "B.Cu" signal "BOTTOM")
		(9 "F.Adhes" user "F.Adhesive")
		(11 "B.Adhes" user "B.Adhesive")
		(13 "F.Paste" user "Package Geometry/Pastemask Top")
		(15 "B.Paste" user "Package Geometry/Pastemask Bottom")
		(5 "F.SilkS" user "Ref Des/Silkscreen Top")
		(7 "B.SilkS" user "Ref Des/Silkscreen Bottom")
		(1 "F.Mask" user "Board Geometry/Soldermask Top")
		(3 "B.Mask" user "Board Geometry/Soldermask Bottom")
		(17 "Dwgs.User" user "User.Drawings")
		(19 "Cmts.User" user "User.Comments")
		(21 "Eco1.User" user "User.Eco1")
		(23 "Eco2.User" user "User.Eco2")
		(25 "Edge.Cuts" user "Board Geometry/Outline")
		(27 "Margin" user)
		(31 "F.CrtYd" user "Package Geometry/Place Bound Top")
		(29 "B.CrtYd" user "Package Geometry/Place Bound Bottom")
		(35 "F.Fab" user "Ref Des/Assembly Top")
		(33 "B.Fab" user "Ref Des/Assembly Bottom")
	)
	(footprint ""
		(layer "F.Cu")
		(at 71.393558 -65.082674 -90)
		(property "Reference" "R3082"
			(at 0 0 270)
			(layer "F.SilkS")
			(hide yes)
			(effects
				(font
					(size 1.27 1.27)
				)
			)
		)
		(property "Value" ""
			(at 0 0 270)
			(layer "F.Fab")
			(effects
				(font
					(size 1.27 1.27)
				)
			)
		)
		(duplicate_pad_numbers_are_jumpers no)
		(fp_line
			(start -0.7874 0.4064)
			(end -0.7874 -0.4064)
			(stroke
				(width 0.1524)
				(type default)
			)
			(layer "F.SilkS")
		)
		(fp_line
			(start 0.7874 0.4064)
			(end -0.7874 0.4064)
			(stroke
				(width 0.1524)
				(type default)
			)
			(layer "F.SilkS")
		)
		(fp_line
			(start -0.7874 -0.4064)
			(end 0.7874 -0.4064)
			(stroke
				(width 0.1524)
				(type default)
			)
			(layer "F.SilkS")
		)
		(fp_line
			(start 0.7874 -0.4064)
			(end 0.7874 0.4064)
			(stroke
				(width 0.1524)
				(type default)
			)
			(layer "F.SilkS")
		)
		(fp_line
			(start -0.67945 0.3048)
			(end -0.67945 -0.305054)
			(stroke
				(width 0.1)
				(type default)
			)
			(layer "F.Fab")
		)
		(fp_line
			(start -0.12065 0.3048)
			(end -0.67945 0.3048)
			(stroke
				(width 0.1)
				(type default)
			)
			(layer "F.Fab")
		)
		(fp_line
			(start 0.120396 0.3048)
			(end 0.120396 0.2794)
			(stroke
				(width 0.1)
				(type default)
			)
			(layer "F.Fab")
		)
		(fp_line
			(start 0.67945 0.3048)
			(end 0.120396 0.3048)
			(stroke
				(width 0.1)
				(type default)
			)
			(layer "F.Fab")
		)
		(fp_line
			(start -0.12065 0.2794)
			(end -0.12065 0.3048)
			(stroke
				(width 0.1)
				(type default)
			)
			(layer "F.Fab")
		)
		(fp_line
			(start 0.120396 0.2794)
			(end -0.12065 0.2794)
			(stroke
				(width 0.1)
				(type default)
			)
			(layer "F.Fab")
		)
		(fp_line
			(start -0.12065 -0.2794)
			(end 0.12065 -0.2794)
			(stroke
				(width 0.1)
				(type default)
			)
			(layer "F.Fab")
		)
		(fp_line
			(start 0.12065 -0.2794)
			(end 0.12065 -0.3048)
			(stroke
				(width 0.1)
				(type default)
			)
			(layer "F.Fab")
		)
		(fp_line
			(start 0.12065 -0.3048)
			(end 0.67945 -0.3048)
			(stroke
				(width 0.1)
				(type default)
			)
			(layer "F.Fab")
		)
		(fp_line
			(start 0.67945 -0.3048)
			(end 0.67945 0.3048)
			(stroke
				(width 0.1)
				(type default)
			)
			(layer "F.Fab")
		)
		(fp_line
			(start -0.67945 -0.305054)
			(end -0.12065 -0.305054)
			(stroke
				(width 0.1)
				(type default)
			)
			(layer "F.Fab")
		)
		(fp_line
			(start -0.12065 -0.305054)
			(end -0.12065 -0.2794)
			(stroke
				(width 0.1)
				(type default)
			)
			(layer "F.Fab")
		)
		(pad "1" smd circle
			(at -0.40005 0 270)
			(size 0 0)
			(layers "F.Cu" "F.Mask" "F.Paste")
			(net "LED_RST_PLD_CPU1_DRAM_AB_N")
		)
		(pad "2" smd circle
			(at 0.40005 0 270)
			(size 0 0)
			(layers "F.Cu" "F.Mask" "F.Paste")
			(net "P3V3_AUX")
		)
	)
	(footprint ""
		(layer "F.Cu")
		(at 367.44783 -252.956314 -90)
		(property "Reference" "C1028"
			(at 0 0 270)
			(layer "F.SilkS")
			(hide yes)
			(effects
				(font
					(size 1.27 1.27)
				)
			)
		)
		(property "Value" ""
			(at 0 0 270)
			(layer "F.Fab")
			(effects
				(font
					(size 1.27 1.27)
				)
			)
		)
		(duplicate_pad_numbers_are_jumpers no)
		(fp_line
			(start -0.7874 0.4064)
			(end -0.7874 -0.4064)
			(stroke
				(width 0.1524)
				(type default)
			)
			(layer "F.SilkS")
		)
		(fp_line
			(start 0.7874 0.4064)
			(end -0.7874 0.4064)
			(stroke
				(width 0.1524)
				(type default)
			)
			(layer "F.SilkS")
		)
		(fp_line
			(start -0.7874 -0.4064)
			(end 0.7874 -0.4064)
			(stroke
				(width 0.1524)
				(type default)
			)
			(layer "F.SilkS")
		)
		(fp_line
			(start 0.7874 -0.4064)
			(end 0.7874 0.4064)
			(stroke
				(width 0.1524)
				(type default)
			)
			(layer "F.SilkS")
		)
		(fp_line
			(start -0.67945 0.3048)
			(end -0.67945 -0.305054)
			(stroke
				(width 0.1)
				(type default)
			)
			(layer "F.Fab")
		)
		(fp_line
			(start -0.12065 0.3048)
			(end -0.67945 0.3048)
			(stroke
				(width 0.1)
				(type default)
			)
			(layer "F.Fab")
		)
		(fp_line
			(start 0.120396 0.3048)
			(end 0.120396 0.2794)
			(stroke
				(width 0.1)
				(type default)
			)
			(layer "F.Fab")
		)
		(fp_line
			(start 0.67945 0.3048)
			(end 0.120396 0.3048)
			(stroke
				(width 0.1)
				(type default)
			)
			(layer "F.Fab")
		)
		(fp_line
			(start -0.12065 0.2794)
			(end -0.12065 0.3048)
			(stroke
				(width 0.1)
				(type default)
			)
			(layer "F.Fab")
		)
		(fp_line
			(start 0.120396 0.2794)
			(end -0.12065 0.2794)
			(stroke
				(width 0.1)
				(type default)
			)
			(layer "F.Fab")
		)
		(fp_line
			(start -0.12065 -0.2794)
			(end 0.12065 -0.2794)
			(stroke
				(width 0.1)
				(type default)
			)
			(layer "F.Fab")
		)
		(fp_line
			(start 0.12065 -0.2794)
			(end 0.12065 -0.3048)
			(stroke
				(width 0.1)
				(type default)
			)
			(layer "F.Fab")
		)
		(fp_line
			(start 0.12065 -0.3048)
			(end 0.67945 -0.3048)
			(stroke
				(width 0.1)
				(type default)
			)
			(layer "F.Fab")
		)
		(fp_line
			(start 0.67945 -0.3048)
			(end 0.67945 0.3048)
			(stroke
				(width 0.1)
				(type default)
			)
			(layer "F.Fab")
		)
		(fp_line
			(start -0.67945 -0.305054)
			(end -0.12065 -0.305054)
			(stroke
				(width 0.1)
				(type default)
			)
			(layer "F.Fab")
		)
		(fp_line
			(start -0.12065 -0.305054)
			(end -0.12065 -0.2794)
			(stroke
				(width 0.1)
				(type default)
			)
			(layer "F.Fab")
		)
		(pad "1" smd circle
			(at -0.40005 0 270)
			(size 0 0)
			(layers "F.Cu" "F.Mask" "F.Paste")
			(net "PVCCIN_CPU0")
		)
		(pad "2" smd circle
			(at 0.40005 0 270)
			(size 0 0)
			(layers "F.Cu" "F.Mask" "F.Paste")
			(net "GND")
		)
	)
	(footprint ""
		(layer "F.Cu")
		(at 404.2664 -385.84886)
		(property "Reference" "ME15"
			(at -9.652 -9.540748 0)
			(unlocked yes)
			(layer "F.SilkS")
			(effects
				(font
					(size 0.7874 0.5842)
					(thickness 0.1524)
				)
				(justify left)
			)
		)
		(property "Value" ""
			(at 0 0 0)
			(layer "F.Fab")
			(effects
				(font
					(size 1.27 1.27)
				)
			)
		)
		(duplicate_pad_numbers_are_jumpers no)
		(zone
			(layer "F.Cu")
			(hatch none 0.5)
			(connect_pads
				(clearance 0)
			)
			(min_thickness 0.25)
			(keepout
				(tracks allowed)
				(vias allowed)
				(pads allowed)
				(copperpour allowed)
				(footprints not_allowed)
			)
			(placement
				(enabled no)
				(sheetname "")
			)
			(fill
				(thermal_gap 0.5)
				(thermal_bridge_width 0.5)
				(island_removal_mode 0)
			)
			(polygon
				(pts
					(arc
						(start 414.26638 -385.84886)
						(mid 394.26642 -385.84886)
						(end 414.26638 -385.84886)
					)
				)
			)
		)
	)
)
